(kicad_pcb
	(version 20260206)
	(generator "pcbnew")
	(generator_version "10.0")
	(general
		(thickness 1.6)
		(legacy_teardrops no)
	)
	(paper "A4")
	(title_block
		(title "panther-plus-userver — 13130-1b_20150205.brd")
		(comment 1 "Honey Badger (Wiwynn) / footprints 1071-1078 of 1509")
	)
	(layers
		(0 "F.Cu" signal "TOP")
		(4 "In1.Cu" signal "L2")
		(6 "In2.Cu" signal "L3")
		(8 "In3.Cu" signal "L4")
		(10 "In4.Cu" signal "L5")
		(12 "In5.Cu" signal "L6")
		(14 "In6.Cu" signal "L7")
		(16 "In7.Cu" signal "L8")
		(18 "In8.Cu" signal "L9")
		(20 "In9.Cu" signal "L10")
		(22 "In10.Cu" signal "L11")
		(2 "B.Cu" signal "BOTTOM")
		(9 "F.Adhes" user "F.Adhesive")
		(11 "B.Adhes" user "B.Adhesive")
		(13 "F.Paste" user "Package Geometry/Pastemask Top")
		(15 "B.Paste" user "Package Geometry/Pastemask Bottom")
		(5 "F.SilkS" user "Ref Des/Silkscreen Top")
		(7 "B.SilkS" user "Ref Des/Silkscreen Bottom")
		(1 "F.Mask" user "Board Geometry/Soldermask Top")
		(3 "B.Mask" user "Board Geometry/Soldermask Bottom")
		(17 "Dwgs.User" user "User.Drawings")
		(19 "Cmts.User" user "User.Comments")
		(21 "Eco1.User" user "User.Eco1")
		(23 "Eco2.User" user "User.Eco2")
		(25 "Edge.Cuts" user "Board Geometry/Outline")
		(27 "Margin" user)
		(31 "F.CrtYd" user "Package Geometry/Place Bound Top")
		(29 "B.CrtYd" user "Package Geometry/Place Bound Bottom")
		(35 "F.Fab" user "Ref Des/Assembly Top")
		(33 "B.Fab" user "Ref Des/Assembly Bottom")
	)
	(footprint ""
		(layer "B.Cu")
		(at 41.4274 -28.7528 -90)
		(property "Reference" "R432"
			(at 0 0 90)
			(layer "B.SilkS")
			(hide yes)
			(effects
				(font
					(size 1.27 1.27)
				)
				(justify mirror)
			)
		)
		(property "Value" "43D2R2F-GP"
			(at -1.7907 -1.1176 270)
			(unlocked yes)
			(layer "B.Fab")
			(hide yes)
			(effects
				(font
					(size 1.016 1.016)
					(thickness 0.1524)
				)
				(justify mirror)
			)
		)
		(property "Device Type" "R402H16"
			(at -1.7907 -2.6416 270)
			(unlocked yes)
			(layer "B.Fab")
			(hide yes)
			(effects
				(font
					(size 1.016 1.016)
					(thickness 0.1524)
				)
				(justify mirror)
			)
		)
		(duplicate_pad_numbers_are_jumpers no)
		(fp_rect
			(start 0.381 0.8382)
			(end -0.381 -0.8382)
			(stroke
				(width 0)
				(type default)
			)
			(fill no)
			(layer "B.CrtYd")
		)
		(fp_rect
			(start 0.381 0.8382)
			(end -0.381 -0.8382)
			(stroke
				(width 0)
				(type default)
			)
			(fill no)
			(layer "B.Fab")
		)
		(pad "1" smd custom
			(at 0 -0.4318 90)
			(size 0.127 0.127)
			(layers "B.Cu" "B.Mask" "B.Paste")
			(net "CLK_100M_CLKBUFF_PCIE_DN")
			(options
				(clearance outline)
				(anchor circle)
			)
			(primitives
				(gr_poly
					(pts
						(arc
							(start -0.2032 0.2794)
							(mid -0.239121 0.264521)
							(end -0.254 0.2286)
						)
						(arc
							(start -0.254 -0.2286)
							(mid -0.239121 -0.264521)
							(end -0.2032 -0.2794)
						)
						(arc
							(start 0.2032 -0.2794)
							(mid 0.239121 -0.264521)
							(end 0.254 -0.2286)
						)
						(arc
							(start 0.254 0.2286)
							(mid 0.239121 0.264521)
							(end 0.2032 0.2794)
						)
					)
					(width 0)
					(fill yes)
				)
			)
		)
		(pad "2" smd custom
			(at 0 0.4318 90)
			(size 0.127 0.127)
			(layers "B.Cu" "B.Mask" "B.Paste")
			(net "GND")
			(options
				(clearance outline)
				(anchor circle)
			)
			(primitives
				(gr_poly
					(pts
						(arc
							(start -0.2032 0.2794)
							(mid -0.239121 0.264521)
							(end -0.254 0.2286)
						)
						(arc
							(start -0.254 -0.2286)
							(mid -0.239121 -0.264521)
							(end -0.2032 -0.2794)
						)
						(arc
							(start 0.2032 -0.2794)
							(mid 0.239121 -0.264521)
							(end 0.254 -0.2286)
						)
						(arc
							(start 0.254 0.2286)
							(mid 0.239121 0.264521)
							(end 0.2032 0.2794)
						)
					)
					(width 0)
					(fill yes)
				)
			)
		)
	)
	(footprint ""
		(layer "B.Cu")
		(at 110.4646 -37.592)
		(property "Reference" "C194"
			(at 0 0 0)
			(layer "B.SilkS")
			(hide yes)
			(effects
				(font
					(size 1.27 1.27)
				)
				(justify mirror)
			)
		)
		(property "Value" "SC1U10V2KX-1GP"
			(at -1.1811 -2.7051 0)
			(unlocked yes)
			(layer "B.Fab")
			(hide yes)
			(effects
				(font
					(size 1.016 1.016)
					(thickness 0.1524)
				)
				(justify mirror)
			)
		)
		(property "Device Type" "C402H22"
			(at -1.1811 -4.2291 0)
			(unlocked yes)
			(layer "B.Fab")
			(hide yes)
			(effects
				(font
					(size 1.016 1.016)
					(thickness 0.1524)
				)
				(justify mirror)
			)
		)
		(duplicate_pad_numbers_are_jumpers no)
		(fp_rect
			(start 0.381 0.7366)
			(end -0.381 -0.7366)
			(stroke
				(width 0)
				(type default)
			)
			(fill no)
			(layer "B.CrtYd")
		)
		(fp_rect
			(start 0.381 0.7366)
			(end -0.381 -0.7366)
			(stroke
				(width 0)
				(type default)
			)
			(fill no)
			(layer "B.Fab")
		)
		(pad "1" smd custom
			(at 0 -0.4572 180)
			(size 0.1143 0.1143)
			(layers "B.Cu" "B.Mask" "B.Paste")
			(net "PVCCP")
			(options
				(clearance outline)
				(anchor circle)
			)
			(primitives
				(gr_poly
					(pts
						(arc
							(start -0.254 0.1778)
							(mid -0.239121 0.213721)
							(end -0.2032 0.2286)
						)
						(arc
							(start 0.2032 0.2286)
							(mid 0.239121 0.213721)
							(end 0.254 0.1778)
						)
						(arc
							(start 0.254 -0.1778)
							(mid 0.239121 -0.213721)
							(end 0.2032 -0.2286)
						)
						(arc
							(start -0.2032 -0.2286)
							(mid -0.239121 -0.213721)
							(end -0.254 -0.1778)
						)
					)
					(width 0)
					(fill yes)
				)
			)
		)
		(pad "2" smd custom
			(at 0 0.4572 180)
			(size 0.1143 0.1143)
			(layers "B.Cu" "B.Mask" "B.Paste")
			(net "GND")
			(options
				(clearance outline)
				(anchor circle)
			)
			(primitives
				(gr_poly
					(pts
						(arc
							(start -0.254 0.1778)
							(mid -0.239121 0.213721)
							(end -0.2032 0.2286)
						)
						(arc
							(start 0.2032 0.2286)
							(mid 0.239121 0.213721)
							(end 0.254 0.1778)
						)
						(arc
							(start 0.254 -0.1778)
							(mid 0.239121 -0.213721)
							(end 0.2032 -0.2286)
						)
						(arc
							(start -0.2032 -0.2286)
							(mid -0.239121 -0.213721)
							(end -0.254 -0.1778)
						)
					)
					(width 0)
					(fill yes)
				)
			)
		)
	)
	(footprint ""
		(layer "B.Cu")
		(at 94.168468 -35.921696 180)
		(property "Reference" "C203"
			(at 0 0 0)
			(layer "B.SilkS")
			(hide yes)
			(effects
				(font
					(size 1.27 1.27)
				)
				(justify mirror)
			)
		)
		(property "Value" "SC1U10V2KX-1GP"
			(at -1.1811 -2.7051 180)
			(unlocked yes)
			(layer "B.Fab")
			(hide yes)
			(effects
				(font
					(size 1.016 1.016)
					(thickness 0.1524)
				)
				(justify mirror)
			)
		)
		(property "Device Type" "C402H22"
			(at -1.1811 -4.2291 180)
			(unlocked yes)
			(layer "B.Fab")
			(hide yes)
			(effects
				(font
					(size 1.016 1.016)
					(thickness 0.1524)
				)
				(justify mirror)
			)
		)
		(duplicate_pad_numbers_are_jumpers no)
		(fp_rect
			(start 0.381 0.7366)
			(end -0.381 -0.7366)
			(stroke
				(width 0)
				(type default)
			)
			(fill no)
			(layer "B.CrtYd")
		)
		(fp_rect
			(start 0.381 0.7366)
			(end -0.381 -0.7366)
			(stroke
				(width 0)
				(type default)
			)
			(fill no)
			(layer "B.Fab")
		)
		(pad "1" smd custom
			(at 0 -0.4572)
			(size 0.1143 0.1143)
			(layers "B.Cu" "B.Mask" "B.Paste")
			(net "P1V0_STBY")
			(options
				(clearance outline)
				(anchor circle)
			)
			(primitives
				(gr_poly
					(pts
						(arc
							(start -0.254 0.1778)
							(mid -0.239121 0.213721)
							(end -0.2032 0.2286)
						)
						(arc
							(start 0.2032 0.2286)
							(mid 0.239121 0.213721)
							(end 0.254 0.1778)
						)
						(arc
							(start 0.254 -0.1778)
							(mid 0.239121 -0.213721)
							(end 0.2032 -0.2286)
						)
						(arc
							(start -0.2032 -0.2286)
							(mid -0.239121 -0.213721)
							(end -0.254 -0.1778)
						)
					)
					(width 0)
					(fill yes)
				)
			)
		)
		(pad "2" smd custom
			(at 0 0.4572)
			(size 0.1143 0.1143)
			(layers "B.Cu" "B.Mask" "B.Paste")
			(net "GND")
			(options
				(clearance outline)
				(anchor circle)
			)
			(primitives
				(gr_poly
					(pts
						(arc
							(start -0.254 0.1778)
							(mid -0.239121 0.213721)
							(end -0.2032 0.2286)
						)
						(arc
							(start 0.2032 0.2286)
							(mid 0.239121 0.213721)
							(end 0.254 0.1778)
						)
						(arc
							(start 0.254 -0.1778)
							(mid 0.239121 -0.213721)
							(end 0.2032 -0.2286)
						)
						(arc
							(start -0.2032 -0.2286)
							(mid -0.239121 -0.213721)
							(end -0.254 -0.1778)
						)
					)
					(width 0)
					(fill yes)
				)
			)
		)
	)
	(footprint ""
		(layer "B.Cu")
		(at 74.676 -24.7904 90)
		(property "Reference" "R375"
			(at 0 0 90)
			(layer "B.SilkS")
			(hide yes)
			(effects
				(font
					(size 1.27 1.27)
				)
				(justify mirror)
			)
		)
		(property "Value" "10KR2F-2-GP"
			(at -0.064008 -3.993896 90)
			(unlocked yes)
			(layer "B.Fab")
			(hide yes)
			(effects
				(font
					(size 1.016 1.016)
					(thickness 0.1524)
				)
				(justify mirror)
			)
		)
		(property "Device Type" "R402H16"
			(at -0.064008 -5.517896 90)
			(unlocked yes)
			(layer "B.Fab")
			(hide yes)
			(effects
				(font
					(size 1.016 1.016)
					(thickness 0.1524)
				)
				(justify mirror)
			)
		)
		(duplicate_pad_numbers_are_jumpers no)
		(fp_rect
			(start 0.381 0.8382)
			(end -0.381 -0.8382)
			(stroke
				(width 0)
				(type default)
			)
			(fill no)
			(layer "B.CrtYd")
		)
		(fp_rect
			(start 0.381 0.8382)
			(end -0.381 -0.8382)
			(stroke
				(width 0)
				(type default)
			)
			(fill no)
			(layer "B.Fab")
		)
		(pad "1" smd custom
			(at 0 -0.4318 270)
			(size 0.127 0.127)
			(layers "B.Cu" "B.Mask" "B.Paste")
			(net "P3V3_CPU")
			(options
				(clearance outline)
				(anchor circle)
			)
			(primitives
				(gr_poly
					(pts
						(arc
							(start -0.2032 0.2794)
							(mid -0.239121 0.264521)
							(end -0.254 0.2286)
						)
						(arc
							(start -0.254 -0.2286)
							(mid -0.239121 -0.264521)
							(end -0.2032 -0.2794)
						)
						(arc
							(start 0.2032 -0.2794)
							(mid 0.239121 -0.264521)
							(end 0.254 -0.2286)
						)
						(arc
							(start 0.254 0.2286)
							(mid 0.239121 0.264521)
							(end 0.2032 0.2794)
						)
					)
					(width 0)
					(fill yes)
				)
			)
		)
		(pad "2" smd custom
			(at 0 0.4318 270)
			(size 0.127 0.127)
			(layers "B.Cu" "B.Mask" "B.Paste")
			(net "GBE_SMBCLK")
			(options
				(clearance outline)
				(anchor circle)
			)
			(primitives
				(gr_poly
					(pts
						(arc
							(start -0.2032 0.2794)
							(mid -0.239121 0.264521)
							(end -0.254 0.2286)
						)
						(arc
							(start -0.254 -0.2286)
							(mid -0.239121 -0.264521)
							(end -0.2032 -0.2794)
						)
						(arc
							(start 0.2032 -0.2794)
							(mid 0.239121 -0.264521)
							(end 0.254 -0.2286)
						)
						(arc
							(start 0.254 0.2286)
							(mid 0.239121 0.264521)
							(end 0.2032 0.2794)
						)
					)
					(width 0)
					(fill yes)
				)
			)
		)
	)
	(footprint ""
		(layer "B.Cu")
		(at 74.4728 -38.7858 180)
		(property "Reference" "R324"
			(at 0 0 0)
			(layer "B.SilkS")
			(hide yes)
			(effects
				(font
					(size 1.27 1.27)
				)
				(justify mirror)
			)
		)
		(property "Value" "0R2J-2-GP"
			(at -0.064008 -3.993896 180)
			(unlocked yes)
			(layer "B.Fab")
			(hide yes)
			(effects
				(font
					(size 1.016 1.016)
					(thickness 0.1524)
				)
				(justify mirror)
			)
		)
		(property "Device Type" "R402H16"
			(at -0.064008 -5.517896 180)
			(unlocked yes)
			(layer "B.Fab")
			(hide yes)
			(effects
				(font
					(size 1.016 1.016)
					(thickness 0.1524)
				)
				(justify mirror)
			)
		)
		(duplicate_pad_numbers_are_jumpers no)
		(fp_rect
			(start 0.381 0.8382)
			(end -0.381 -0.8382)
			(stroke
				(width 0)
				(type default)
			)
			(fill no)
			(layer "B.CrtYd")
		)
		(fp_rect
			(start 0.381 0.8382)
			(end -0.381 -0.8382)
			(stroke
				(width 0)
				(type default)
			)
			(fill no)
			(layer "B.Fab")
		)
		(pad "1" smd custom
			(at 0 -0.4318)
			(size 0.127 0.127)
			(layers "B.Cu" "B.Mask" "B.Paste")
			(net "CPU_RSVD10")
			(options
				(clearance outline)
				(anchor circle)
			)
			(primitives
				(gr_poly
					(pts
						(arc
							(start -0.2032 0.2794)
							(mid -0.239121 0.264521)
							(end -0.254 0.2286)
						)
						(arc
							(start -0.254 -0.2286)
							(mid -0.239121 -0.264521)
							(end -0.2032 -0.2794)
						)
						(arc
							(start 0.2032 -0.2794)
							(mid 0.239121 -0.264521)
							(end 0.254 -0.2286)
						)
						(arc
							(start 0.254 0.2286)
							(mid 0.239121 0.264521)
							(end 0.2032 0.2794)
						)
					)
					(width 0)
					(fill yes)
				)
			)
		)
		(pad "2" smd custom
			(at 0 0.4318)
			(size 0.127 0.127)
			(layers "B.Cu" "B.Mask" "B.Paste")
			(net "GND")
			(options
				(clearance outline)
				(anchor circle)
			)
			(primitives
				(gr_poly
					(pts
						(arc
							(start -0.2032 0.2794)
							(mid -0.239121 0.264521)
							(end -0.254 0.2286)
						)
						(arc
							(start -0.254 -0.2286)
							(mid -0.239121 -0.264521)
							(end -0.2032 -0.2794)
						)
						(arc
							(start 0.2032 -0.2794)
							(mid 0.239121 -0.264521)
							(end 0.254 -0.2286)
						)
						(arc
							(start 0.254 0.2286)
							(mid 0.239121 0.264521)
							(end 0.2032 0.2794)
						)
					)
					(width 0)
					(fill yes)
				)
			)
		)
	)
	(footprint ""
		(layer "B.Cu")
		(at 99.947984 -27.321002)
		(property "Reference" "C244"
			(at 0 0 0)
			(layer "B.SilkS")
			(hide yes)
			(effects
				(font
					(size 1.27 1.27)
				)
				(justify mirror)
			)
		)
		(property "Value" "SCD1U16V2KX-L-GP"
			(at -1.1811 -2.7051 0)
			(unlocked yes)
			(layer "B.Fab")
			(hide yes)
			(effects
				(font
					(size 1.016 1.016)
					(thickness 0.1524)
				)
				(justify mirror)
			)
		)
		(property "Device Type" "C402H22"
			(at -1.1811 -4.2291 0)
			(unlocked yes)
			(layer "B.Fab")
			(hide yes)
			(effects
				(font
					(size 1.016 1.016)
					(thickness 0.1524)
				)
				(justify mirror)
			)
		)
		(duplicate_pad_numbers_are_jumpers no)
		(fp_rect
			(start 0.381 0.7366)
			(end -0.381 -0.7366)
			(stroke
				(width 0)
				(type default)
			)
			(fill no)
			(layer "B.CrtYd")
		)
		(fp_rect
			(start 0.381 0.7366)
			(end -0.381 -0.7366)
			(stroke
				(width 0)
				(type default)
			)
			(fill no)
			(layer "B.Fab")
		)
		(pad "1" smd custom
			(at 0 -0.4572 180)
			(size 0.1143 0.1143)
			(layers "B.Cu" "B.Mask" "B.Paste")
			(net "M_B_VREF")
			(options
				(clearance outline)
				(anchor circle)
			)
			(primitives
				(gr_poly
					(pts
						(arc
							(start -0.254 0.1778)
							(mid -0.239121 0.213721)
							(end -0.2032 0.2286)
						)
						(arc
							(start 0.2032 0.2286)
							(mid 0.239121 0.213721)
							(end 0.254 0.1778)
						)
						(arc
							(start 0.254 -0.1778)
							(mid 0.239121 -0.213721)
							(end 0.2032 -0.2286)
						)
						(arc
							(start -0.2032 -0.2286)
							(mid -0.239121 -0.213721)
							(end -0.254 -0.1778)
						)
					)
					(width 0)
					(fill yes)
				)
			)
		)
		(pad "2" smd custom
			(at 0 0.4572 180)
			(size 0.1143 0.1143)
			(layers "B.Cu" "B.Mask" "B.Paste")
			(net "GND")
			(options
				(clearance outline)
				(anchor circle)
			)
			(primitives
				(gr_poly
					(pts
						(arc
							(start -0.254 0.1778)
							(mid -0.239121 0.213721)
							(end -0.2032 0.2286)
						)
						(arc
							(start 0.2032 0.2286)
							(mid 0.239121 0.213721)
							(end 0.254 0.1778)
						)
						(arc
							(start 0.254 -0.1778)
							(mid 0.239121 -0.213721)
							(end 0.2032 -0.2286)
						)
						(arc
							(start -0.2032 -0.2286)
							(mid -0.239121 -0.213721)
							(end -0.254 -0.1778)
						)
					)
					(width 0)
					(fill yes)
				)
			)
		)
	)
	(footprint ""
		(layer "B.Cu")
		(at 133.731 -31.115 -90)
		(property "Reference" "C138"
			(at 0 0 90)
			(layer "B.SilkS")
			(hide yes)
			(effects
				(font
					(size 1.27 1.27)
				)
				(justify mirror)
			)
		)
		(property "Value" "SCD1U10V2KX-5GP"
			(at -1.1811 -2.7051 270)
			(unlocked yes)
			(layer "B.Fab")
			(hide yes)
			(effects
				(font
					(size 1.016 1.016)
					(thickness 0.1524)
				)
				(justify mirror)
			)
		)
		(property "Device Type" "C402H22"
			(at -1.1811 -4.2291 270)
			(unlocked yes)
			(layer "B.Fab")
			(hide yes)
			(effects
				(font
					(size 1.016 1.016)
					(thickness 0.1524)
				)
				(justify mirror)
			)
		)
		(duplicate_pad_numbers_are_jumpers no)
		(fp_rect
			(start 0.381 0.7366)
			(end -0.381 -0.7366)
			(stroke
				(width 0)
				(type default)
			)
			(fill no)
			(layer "B.CrtYd")
		)
		(fp_rect
			(start 0.381 0.7366)
			(end -0.381 -0.7366)
			(stroke
				(width 0)
				(type default)
			)
			(fill no)
			(layer "B.Fab")
		)
		(pad "1" smd custom
			(at 0 -0.4572 90)
			(size 0.1143 0.1143)
			(layers "B.Cu" "B.Mask" "B.Paste")
			(net "P3V3_STBY")
			(options
				(clearance outline)
				(anchor circle)
			)
			(primitives
				(gr_poly
					(pts
						(arc
							(start -0.254 0.1778)
							(mid -0.239121 0.213721)
							(end -0.2032 0.2286)
						)
						(arc
							(start 0.2032 0.2286)
							(mid 0.239121 0.213721)
							(end 0.254 0.1778)
						)
						(arc
							(start 0.254 -0.1778)
							(mid 0.239121 -0.213721)
							(end 0.2032 -0.2286)
						)
						(arc
							(start -0.2032 -0.2286)
							(mid -0.239121 -0.213721)
							(end -0.254 -0.1778)
						)
					)
					(width 0)
					(fill yes)
				)
			)
		)
		(pad "2" smd custom
			(at 0 0.4572 90)
			(size 0.1143 0.1143)
			(layers "B.Cu" "B.Mask" "B.Paste")
			(net "GND")
			(options
				(clearance outline)
				(anchor circle)
			)
			(primitives
				(gr_poly
					(pts
						(arc
							(start -0.254 0.1778)
							(mid -0.239121 0.213721)
							(end -0.2032 0.2286)
						)
						(arc
							(start 0.2032 0.2286)
							(mid 0.239121 0.213721)
							(end 0.254 0.1778)
						)
						(arc
							(start 0.254 -0.1778)
							(mid 0.239121 -0.213721)
							(end 0.2032 -0.2286)
						)
						(arc
							(start -0.2032 -0.2286)
							(mid -0.239121 -0.213721)
							(end -0.254 -0.1778)
						)
					)
					(width 0)
					(fill yes)
				)
			)
		)
	)
	(footprint ""
		(layer "B.Cu")
		(at 131.318 -14.733778 180)
		(property "Reference" "C296"
			(at 0 0 0)
			(layer "B.SilkS")
			(hide yes)
			(effects
				(font
					(size 1.27 1.27)
				)
				(justify mirror)
			)
		)
		(property "Value" "SCD1U16V2KX-3GP"
			(at -1.1811 -2.7051 180)
			(unlocked yes)
			(layer "B.Fab")
			(hide yes)
			(effects
				(font
					(size 1.016 1.016)
					(thickness 0.1524)
				)
				(justify mirror)
			)
		)
		(property "Device Type" "C402H22"
			(at -1.1811 -4.2291 180)
			(unlocked yes)
			(layer "B.Fab")
			(hide yes)
			(effects
				(font
					(size 1.016 1.016)
					(thickness 0.1524)
				)
				(justify mirror)
			)
		)
		(duplicate_pad_numbers_are_jumpers no)
		(fp_rect
			(start 0.381 0.7366)
			(end -0.381 -0.7366)
			(stroke
				(width 0)
				(type default)
			)
			(fill no)
			(layer "B.CrtYd")
		)
		(fp_rect
			(start 0.381 0.7366)
			(end -0.381 -0.7366)
			(stroke
				(width 0)
				(type default)
			)
			(fill no)
			(layer "B.Fab")
		)
		(pad "1" smd custom
			(at 0 -0.4572)
			(size 0.1143 0.1143)
			(layers "B.Cu" "B.Mask" "B.Paste")
			(net "DDR3_M_B_VREF_DQ1")
			(options
				(clearance outline)
				(anchor circle)
			)
			(primitives
				(gr_poly
					(pts
						(arc
							(start -0.254 0.1778)
							(mid -0.239121 0.213721)
							(end -0.2032 0.2286)
						)
						(arc
							(start 0.2032 0.2286)
							(mid 0.239121 0.213721)
							(end 0.254 0.1778)
						)
						(arc
							(start 0.254 -0.1778)
							(mid 0.239121 -0.213721)
							(end 0.2032 -0.2286)
						)
						(arc
							(start -0.2032 -0.2286)
							(mid -0.239121 -0.213721)
							(end -0.254 -0.1778)
						)
					)
					(width 0)
					(fill yes)
				)
			)
		)
		(pad "2" smd custom
			(at 0 0.4572)
			(size 0.1143 0.1143)
			(layers "B.Cu" "B.Mask" "B.Paste")
			(net "GND")
			(options
				(clearance outline)
				(anchor circle)
			)
			(primitives
				(gr_poly
					(pts
						(arc
							(start -0.254 0.1778)
							(mid -0.239121 0.213721)
							(end -0.2032 0.2286)
						)
						(arc
							(start 0.2032 0.2286)
							(mid 0.239121 0.213721)
							(end 0.254 0.1778)
						)
						(arc
							(start 0.254 -0.1778)
							(mid 0.239121 -0.213721)
							(end 0.2032 -0.2286)
						)
						(arc
							(start -0.2032 -0.2286)
							(mid -0.239121 -0.213721)
							(end -0.254 -0.1778)
						)
					)
					(width 0)
					(fill yes)
				)
			)
		)
	)
)
